# S9S_MB_2U (Grand Teton) — schematic netlist excerpt (pin names and nets, part order shuffled) for the footprints in the layout excerpt that follows; sources: Cadence DE-HDL packaged netlist, KiCad conversion of 03242023_DA0F0TMBIJ0_F0T_Motherboard_J_brd_V01_OCP.brd

C1210  Q_CAP  10UF 6.3V 20% X6S  pkg C0402  page 189 : A = P1V05_PCH_AUX ; B = GND
R2734  Q_RES  33.2 1% CHIP  pkg 0402LF  page 114 : A = PWRGD_CHH_CPU0_DIMM1 ; B = PWRGD_FAIL_CPU0_GH

(kicad_pcb
	(version 20260206)
	(generator "pcbnew")
	(generator_version "10.0")
	(general
		(thickness 1.6)
		(legacy_teardrops no)
	)
	(paper "A4")
	(title_block
		(title "03242023_DA0F0TMBIJ0_F0T_Motherboard_J_brd_V01_OCP.brd")
		(comment 1 "Grand Teton / footprints 4668-4669 of 6105")
	)
	(layers
		(0 "F.Cu" signal "TOP")
		(4 "In1.Cu" signal "GND")
		(6 "In2.Cu" signal "IN1")
		(8 "In3.Cu" signal "GND1")
		(10 "In4.Cu" signal "IN2")
		(12 "In5.Cu" signal "GND2")
		(14 "In6.Cu" signal "IN3")
		(16 "In7.Cu" signal "GND3")
		(18 "In8.Cu" signal "VCC")
		(20 "In9.Cu" signal "VCC1")
		(22 "In10.Cu" signal "GND4")
		(24 "In11.Cu" signal "IN4")
		(26 "In12.Cu" signal "GND5")
		(28 "In13.Cu" signal "IN5")
		(30 "In14.Cu" signal "GND6")
		(32 "In15.Cu" signal "IN6")
		(34 "In16.Cu" signal "GND7")
		(2 "B.Cu" signal "BOTTOM")
		(9 "F.Adhes" user "F.Adhesive")
		(11 "B.Adhes" user "B.Adhesive")
		(13 "F.Paste" user "Package Geometry/Pastemask Top")
		(15 "B.Paste" user "Package Geometry/Pastemask Bottom")
		(5 "F.SilkS" user "Ref Des/Silkscreen Top")
		(7 "B.SilkS" user "Ref Des/Silkscreen Bottom")
		(1 "F.Mask" user "Board Geometry/Soldermask Top")
		(3 "B.Mask" user "Board Geometry/Soldermask Bottom")
		(17 "Dwgs.User" user "User.Drawings")
		(19 "Cmts.User" user "User.Comments")
		(21 "Eco1.User" user "User.Eco1")
		(23 "Eco2.User" user "User.Eco2")
		(25 "Edge.Cuts" user "Board Geometry/Outline")
		(27 "Margin" user)
		(31 "F.CrtYd" user "Package Geometry/Place Bound Top")
		(29 "B.CrtYd" user "Package Geometry/Place Bound Bottom")
		(35 "F.Fab" user "Ref Des/Assembly Top")
		(33 "B.Fab" user "Ref Des/Assembly Bottom")
	)
	(footprint ""
		(layer "B.Cu")
		(at 459.982316 -318.608456 90)
		(property "Reference" "R2734"
			(at 0 0 90)
			(layer "B.SilkS")
			(hide yes)
			(effects
				(font
					(size 1.27 1.27)
				)
				(justify mirror)
			)
		)
		(property "Value" ""
			(at 0 0 90)
			(layer "B.Fab")
			(effects
				(font
					(size 1.27 1.27)
				)
				(justify mirror)
			)
		)
		(duplicate_pad_numbers_are_jumpers no)
		(fp_line
			(start 0.7874 -0.4064)
			(end -0.7874 -0.4064)
			(stroke
				(width 0.1524)
				(type default)
			)
			(layer "B.SilkS")
		)
		(fp_line
			(start -0.7874 -0.4064)
			(end -0.7874 0.4064)
			(stroke
				(width 0.1524)
				(type default)
			)
			(layer "B.SilkS")
		)
		(fp_line
			(start 0.7874 0.4064)
			(end 0.7874 -0.4064)
			(stroke
				(width 0.1524)
				(type default)
			)
			(layer "B.SilkS")
		)
		(fp_line
			(start -0.7874 0.4064)
			(end 0.7874 0.4064)
			(stroke
				(width 0.1524)
				(type default)
			)
			(layer "B.SilkS")
		)
		(fp_line
			(start 0.67945 -0.305054)
			(end 0.12065 -0.305054)
			(stroke
				(width 0.1)
				(type default)
			)
			(layer "B.Fab")
		)
		(fp_line
			(start 0.12065 -0.305054)
			(end 0.12065 -0.2794)
			(stroke
				(width 0.1)
				(type default)
			)
			(layer "B.Fab")
		)
		(fp_line
			(start -0.12065 -0.3048)
			(end -0.67945 -0.3048)
			(stroke
				(width 0.1)
				(type default)
			)
			(layer "B.Fab")
		)
		(fp_line
			(start -0.67945 -0.3048)
			(end -0.67945 0.3048)
			(stroke
				(width 0.1)
				(type default)
			)
			(layer "B.Fab")
		)
		(fp_line
			(start 0.12065 -0.2794)
			(end -0.12065 -0.2794)
			(stroke
				(width 0.1)
				(type default)
			)
			(layer "B.Fab")
		)
		(fp_line
			(start -0.12065 -0.2794)
			(end -0.12065 -0.3048)
			(stroke
				(width 0.1)
				(type default)
			)
			(layer "B.Fab")
		)
		(fp_line
			(start 0.12065 0.2794)
			(end 0.12065 0.3048)
			(stroke
				(width 0.1)
				(type default)
			)
			(layer "B.Fab")
		)
		(fp_line
			(start -0.120396 0.2794)
			(end 0.12065 0.2794)
			(stroke
				(width 0.1)
				(type default)
			)
			(layer "B.Fab")
		)
		(fp_line
			(start 0.67945 0.3048)
			(end 0.67945 -0.305054)
			(stroke
				(width 0.1)
				(type default)
			)
			(layer "B.Fab")
		)
		(fp_line
			(start 0.12065 0.3048)
			(end 0.67945 0.3048)
			(stroke
				(width 0.1)
				(type default)
			)
			(layer "B.Fab")
		)
		(fp_line
			(start -0.120396 0.3048)
			(end -0.120396 0.2794)
			(stroke
				(width 0.1)
				(type default)
			)
			(layer "B.Fab")
		)
		(fp_line
			(start -0.67945 0.3048)
			(end -0.120396 0.3048)
			(stroke
				(width 0.1)
				(type default)
			)
			(layer "B.Fab")
		)
		(pad "1" smd circle
			(at 0.40005 0 270)
			(size 0 0)
			(layers "B.Cu" "B.Mask" "B.Paste")
			(net "PWRGD_CHH_CPU0_DIMM1")
		)
		(pad "2" smd circle
			(at -0.40005 0 270)
			(size 0 0)
			(layers "B.Cu" "B.Mask" "B.Paste")
			(net "PWRGD_FAIL_CPU0_GH")
		)
	)
	(footprint ""
		(layer "B.Cu")
		(at 335.915254 -46.888146 -90)
		(property "Reference" "C1210"
			(at 0 0 90)
			(layer "B.SilkS")
			(hide yes)
			(effects
				(font
					(size 1.27 1.27)
				)
				(justify mirror)
			)
		)
		(property "Value" ""
			(at 0 0 90)
			(layer "B.Fab")
			(effects
				(font
					(size 1.27 1.27)
				)
				(justify mirror)
			)
		)
		(duplicate_pad_numbers_are_jumpers no)
		(fp_line
			(start -0.7874 0.4064)
			(end 0.7874 0.4064)
			(stroke
				(width 0.1524)
				(type default)
			)
			(layer "B.SilkS")
		)
		(fp_line
			(start 0.7874 0.4064)
			(end 0.7874 -0.4064)
			(stroke
				(width 0.1524)
				(type default)
			)
			(layer "B.SilkS")
		)
		(fp_line
			(start -0.7874 -0.4064)
			(end -0.7874 0.4064)
			(stroke
				(width 0.1524)
				(type default)
			)
			(layer "B.SilkS")
		)
		(fp_line
			(start 0.7874 -0.4064)
			(end -0.7874 -0.4064)
			(stroke
				(width 0.1524)
				(type default)
			)
			(layer "B.SilkS")
		)
		(fp_line
			(start -0.67945 0.3048)
			(end -0.120396 0.3048)
			(stroke
				(width 0.1)
				(type default)
			)
			(layer "B.Fab")
		)
		(fp_line
			(start -0.120396 0.3048)
			(end -0.120396 0.2794)
			(stroke
				(width 0.1)
				(type default)
			)
			(layer "B.Fab")
		)
		(fp_line
			(start 0.12065 0.3048)
			(end 0.67945 0.3048)
			(stroke
				(width 0.1)
				(type default)
			)
			(layer "B.Fab")
		)
		(fp_line
			(start 0.67945 0.3048)
			(end 0.67945 -0.305054)
			(stroke
				(width 0.1)
				(type default)
			)
			(layer "B.Fab")
		)
		(fp_line
			(start -0.120396 0.2794)
			(end 0.12065 0.2794)
			(stroke
				(width 0.1)
				(type default)
			)
			(layer "B.Fab")
		)
		(fp_line
			(start 0.12065 0.2794)
			(end 0.12065 0.3048)
			(stroke
				(width 0.1)
				(type default)
			)
			(layer "B.Fab")
		)
		(fp_line
			(start -0.12065 -0.2794)
			(end -0.12065 -0.3048)
			(stroke
				(width 0.1)
				(type default)
			)
			(layer "B.Fab")
		)
		(fp_line
			(start 0.12065 -0.2794)
			(end -0.12065 -0.2794)
			(stroke
				(width 0.1)
				(type default)
			)
			(layer "B.Fab")
		)
		(fp_line
			(start -0.67945 -0.3048)
			(end -0.67945 0.3048)
			(stroke
				(width 0.1)
				(type default)
			)
			(layer "B.Fab")
		)
		(fp_line
			(start -0.12065 -0.3048)
			(end -0.67945 -0.3048)
			(stroke
				(width 0.1)
				(type default)
			)
			(layer "B.Fab")
		)
		(fp_line
			(start 0.12065 -0.305054)
			(end 0.12065 -0.2794)
			(stroke
				(width 0.1)
				(type default)
			)
			(layer "B.Fab")
		)
		(fp_line
			(start 0.67945 -0.305054)
			(end 0.12065 -0.305054)
			(stroke
				(width 0.1)
				(type default)
			)
			(layer "B.Fab")
		)
		(pad "1" smd circle
			(at 0.40005 0 90)
			(size 0 0)
			(layers "B.Cu" "B.Mask" "B.Paste")
			(net "P1V05_PCH_AUX")
		)
		(pad "2" smd circle
			(at -0.40005 0 90)
			(size 0 0)
			(layers "B.Cu" "B.Mask" "B.Paste")
			(net "GND")
		)
	)
)
